(kicad_pcb
	(version 20241229)
	(generator "pcbnew")
	(generator_version "9.0")
	(general
		(thickness 1.294)
		(legacy_teardrops no)
	)
	(paper "A3")
	(title_block
		(title "Kintex 410T devboard")
		(date "2024-04-03")
		(rev "1.1.2")
		(comment 9 "footprints 227-229 of 975")
	)
	(layers
		(0 "F.Cu" mixed)
		(4 "In1.Cu" power)
		(6 "In2.Cu" power)
		(8 "In3.Cu" mixed)
		(10 "In4.Cu" power)
		(12 "In5.Cu" mixed)
		(14 "In6.Cu" power)
		(16 "In7.Cu" mixed)
		(18 "In8.Cu" power)
		(2 "B.Cu" mixed)
		(9 "F.Adhes" user "F.Adhesive")
		(11 "B.Adhes" user "B.Adhesive")
		(13 "F.Paste" user)
		(15 "B.Paste" user)
		(5 "F.SilkS" user "F.Silkscreen")
		(7 "B.SilkS" user "B.Silkscreen")
		(1 "F.Mask" user)
		(3 "B.Mask" user)
		(17 "Dwgs.User" user "User.Drawings")
		(19 "Cmts.User" user "User.Comments")
		(21 "Eco1.User" user "User.Eco1")
		(23 "Eco2.User" user "User.Eco2")
		(25 "Edge.Cuts" user)
		(27 "Margin" user)
		(31 "F.CrtYd" user "F.Courtyard")
		(29 "B.CrtYd" user "B.Courtyard")
		(35 "F.Fab" user)
		(33 "B.Fab" user)
	)
	(footprint "antmicro-footprints:LGA-33_7x7mm_P0.65mm"
		(layer "F.Cu")
		(at 176.1125 170.825 180)
		(property "Reference" "U32"
			(at 6.0625 3.625 180)
			(layer "F.SilkS")
			(effects
				(font
					(size 0.7 0.7)
					(thickness 0.15)
				)
				(justify left bottom)
			)
		)
		(property "Value" "MPM54304GMN"
			(at -3.5 0.3 180)
			(layer "F.Fab")
			(effects
				(font
					(size 0.7 0.7)
					(thickness 0.15)
				)
				(justify left bottom)
			)
		)
		(property "Description" "DC-DC Switching Synchronous Step-Down Regulator, Multi Output, 4-16V in, 1V/3.3V, 4.2/3A out, LGA33"
			(at 0 0 180)
			(layer "F.Fab")
			(hide yes)
			(effects
				(font
					(size 1.27 1.27)
					(thickness 0.15)
				)
			)
		)
		(property "Author" "Antmicro"
			(at 352.225 341.65 0)
			(layer "F.Fab")
			(hide yes)
			(effects
				(font
					(size 1 1)
					(thickness 0.15)
				)
			)
		)
		(property "License" "Apache-2.0"
			(at 352.225 341.65 0)
			(layer "F.Fab")
			(hide yes)
			(effects
				(font
					(size 1 1)
					(thickness 0.15)
				)
			)
		)
		(property "MPN" "MPM54304GMN-0000"
			(at 352.225 341.65 0)
			(layer "F.Fab")
			(hide yes)
			(effects
				(font
					(size 1 1)
					(thickness 0.15)
				)
			)
		)
		(property "Manufacturer" "Monolithic Power Systems"
			(at 352.225 341.65 0)
			(layer "F.Fab")
			(hide yes)
			(effects
				(font
					(size 1 1)
					(thickness 0.15)
				)
			)
		)
		(sheetname "DC-DC Converters")
		(sheetfile "dc-dc.kicad_sch")
		(solder_paste_margin_ratio -0.1)
		(attr smd)
		(fp_line
			(start 3.648 3.648)
			(end 3.648 2.922)
			(stroke
				(width 0.15)
				(type solid)
			)
			(layer "F.SilkS")
		)
		(fp_line
			(start 3.648 -3.65)
			(end 3.648 -2.926)
			(stroke
				(width 0.15)
				(type solid)
			)
			(layer "F.SilkS")
		)
		(fp_line
			(start 2.922 3.648)
			(end 3.648 3.648)
			(stroke
				(width 0.15)
				(type solid)
			)
			(layer "F.SilkS")
		)
		(fp_line
			(start 2.922 -3.65)
			(end 3.648 -3.65)
			(stroke
				(width 0.15)
				(type solid)
			)
			(layer "F.SilkS")
		)
		(fp_line
			(start -2.926 3.648)
			(end -3.65 3.648)
			(stroke
				(width 0.15)
				(type solid)
			)
			(layer "F.SilkS")
		)
		(fp_line
			(start -3.65 3.648)
			(end -3.65 2.922)
			(stroke
				(width 0.15)
				(type solid)
			)
			(layer "F.SilkS")
		)
		(fp_line
			(start -3.665 -2.928)
			(end -3.665 -3.653)
			(stroke
				(width 0.15)
				(type solid)
			)
			(layer "F.SilkS")
		)
		(fp_line
			(start -3.665 -3.653)
			(end -2.94 -3.653)
			(stroke
				(width 0.15)
				(type solid)
			)
			(layer "F.SilkS")
		)
		(fp_circle
			(center -3.8 -1.925)
			(end -3.75 -1.925)
			(stroke
				(width 0.15)
				(type solid)
			)
			(fill yes)
			(layer "F.SilkS")
		)
		(fp_rect
			(start -4 -4)
			(end 3.999 3.999)
			(stroke
				(width 0.05)
				(type solid)
			)
			(fill no)
			(layer "F.CrtYd")
		)
		(fp_line
			(start 3.499 3.499)
			(end 3.499 -3.5)
			(stroke
				(width 0.15)
				(type solid)
			)
			(layer "F.Fab")
		)
		(fp_line
			(start 3.499 -3.5)
			(end -3.5 -3.5)
			(stroke
				(width 0.15)
				(type solid)
			)
			(layer "F.Fab")
		)
		(fp_line
			(start -3.101 -3.5)
			(end -3.5 -3.101)
			(stroke
				(width 0.15)
				(type solid)
			)
			(layer "F.Fab")
		)
		(fp_line
			(start -3.5 3.499)
			(end 3.499 3.499)
			(stroke
				(width 0.15)
				(type solid)
			)
			(layer "F.Fab")
		)
		(fp_line
			(start -3.5 -3.5)
			(end -3.5 3.499)
			(stroke
				(width 0.15)
				(type solid)
			)
			(layer "F.Fab")
		)
		(pad "1" smd rect
			(at -3.138 -1.625 270)
			(size 0.3 1.125)
			(layers "F.Cu" "F.Mask" "F.Paste")
			(net 739 "/DC-DC Converters/5V_local")
			(pinfunction "VOUT3")
			(pintype "power_out")
		)
		(pad "2" smd rect
			(at -3.138 -0.975 270)
			(size 0.3 1.125)
			(layers "F.Cu" "F.Mask" "F.Paste")
			(net 1 "GND")
			(pinfunction "GND")
			(pintype "passive")
		)
		(pad "3" smd rect
			(at -3.138 -0.328 270)
			(size 0.3 1.125)
			(layers "F.Cu" "F.Mask" "F.Paste")
			(net 1336 "/I2C.SDA")
			(pinfunction "SDA")
			(pintype "bidirectional")
		)
		(pad "4" smd rect
			(at -3.138 0.325 270)
			(size 0.3 1.125)
			(layers "F.Cu" "F.Mask" "F.Paste")
			(net 1393 "/I2C.QDCDC2_SCL")
			(pinfunction "SCL")
			(pintype "input")
		)
		(pad "5" smd rect
			(at -3.138 0.972 270)
			(size 0.3 1.125)
			(layers "F.Cu" "F.Mask" "F.Paste")
			(net 1 "GND")
			(pinfunction "GND")
			(pintype "passive")
		)
		(pad "6" smd rect
			(at -3.138 1.624 270)
			(size 0.3 1.125)
			(layers "F.Cu" "F.Mask" "F.Paste")
			(net 957 "/DC-DC Converters/FB6")
			(pinfunction "FB2")
			(pintype "input")
		)
		(pad "7" smd rect
			(at -2.926 3.136)
			(size 0.3 1.125)
			(layers "F.Cu" "F.Mask" "F.Paste")
			(net 1 "GND")
			(pinfunction "GND")
			(pintype "passive")
		)
		(pad "8" smd rect
			(at -2.275 3.136)
			(size 0.3 1.125)
			(layers "F.Cu" "F.Mask" "F.Paste")
			(net 736 "/DC-DC Converters/3V3_local_2")
			(pinfunction "VOUT2")
			(pintype "power_out")
		)
		(pad "9" smd rect
			(at -1.625 3.136 180)
			(size 0.3 1.125)
			(layers "F.Cu" "F.Mask" "F.Paste")
			(net 736 "/DC-DC Converters/3V3_local_2")
			(pinfunction "VOUT2")
			(pintype "passive")
		)
		(pad "10" smd rect
			(at -0.975 3.136 180)
			(size 0.3 1.125)
			(layers "F.Cu" "F.Mask" "F.Paste")
			(net 1 "GND")
			(pinfunction "GND")
			(pintype "passive")
		)
		(pad "11" smd rect
			(at -0.328 3.136 180)
			(size 0.3 1.125)
			(layers "F.Cu" "F.Mask" "F.Paste")
			(net 1052 "/DC-DC Converters/SW2")
			(pinfunction "SW2")
			(pintype "power_out")
		)
		(pad "12" smd rect
			(at 0.325 3.136 180)
			(size 0.3 1.125)
			(layers "F.Cu" "F.Mask" "F.Paste")
			(net 1143 "/DC-DC Converters/SW1")
			(pinfunction "SW1")
			(pintype "power_out")
		)
		(pad "13" smd rect
			(at 0.972 3.136 180)
			(size 0.3 1.125)
			(layers "F.Cu" "F.Mask" "F.Paste")
			(net 1 "GND")
			(pinfunction "GND")
			(pintype "passive")
		)
		(pad "14" smd rect
			(at 1.624 3.136 180)
			(size 0.3 1.125)
			(layers "F.Cu" "F.Mask" "F.Paste")
			(net 735 "/DC-DC Converters/3V3_local")
			(pinfunction "VOUT1")
			(pintype "power_out")
		)
		(pad "15" smd rect
			(at 2.273 3.136 180)
			(size 0.3 1.125)
			(layers "F.Cu" "F.Mask" "F.Paste")
			(net 735 "/DC-DC Converters/3V3_local")
			(pinfunction "VOUT1")
			(pintype "passive")
		)
		(pad "16" smd rect
			(at 2.922 3.136 180)
			(size 0.3 1.125)
			(layers "F.Cu" "F.Mask" "F.Paste")
			(net 1 "GND")
			(pinfunction "GND")
			(pintype "passive")
		)
		(pad "17" smd rect
			(at 3.136 1.624 270)
			(size 0.3 1.125)
			(layers "F.Cu" "F.Mask" "F.Paste")
			(net 1 "GND")
			(pinfunction "SGND1")
			(pintype "power_out")
		)
		(pad "18" smd rect
			(at 3.136 0.972 270)
			(size 0.3 1.125)
			(layers "F.Cu" "F.Mask" "F.Paste")
			(net 958 "/DC-DC Converters/FB5")
			(pinfunction "FB1")
			(pintype "input")
		)
		(pad "19" smd rect
			(at 3.136 0.325 270)
			(size 0.3 1.125)
			(layers "F.Cu" "F.Mask" "F.Paste")
			(net 968 "/DC-DC Converters/EN3")
			(pinfunction "EN/SYNCI")
			(pintype "input")
		)
		(pad "20" smd rect
			(at 3.136 -0.328 270)
			(size 0.3 1.125)
			(layers "F.Cu" "F.Mask" "F.Paste")
			(net 1 "GND")
			(pinfunction "GND")
			(pintype "passive")
		)
		(pad "21" smd rect
			(at 3.136 -0.975 270)
			(size 0.3 1.125)
			(layers "F.Cu" "F.Mask" "F.Paste")
			(net 1 "GND")
			(pinfunction "GND")
			(pintype "passive")
		)
		(pad "22" smd rect
			(at 3.136 -1.625 270)
			(size 0.3 1.125)
			(layers "F.Cu" "F.Mask" "F.Paste")
			(net 740 "/DC-DC Converters/1V35_local")
			(pinfunction "VOUT4")
			(pintype "power_out")
		)
		(pad "23" smd rect
			(at 2.922 -3.138)
			(size 0.3 1.125)
			(layers "F.Cu" "F.Mask" "F.Paste")
			(net 740 "/DC-DC Converters/1V35_local")
			(pinfunction "VOUT4")
			(pintype "passive")
		)
		(pad "24" smd rect
			(at 2.273 -3.138)
			(size 0.3 1.125)
			(layers "F.Cu" "F.Mask" "F.Paste")
			(net 965 "/DC-DC Converters/FB8")
			(pinfunction "FB4")
			(pintype "input")
		)
		(pad "25" smd rect
			(at 1.624 -3.138 180)
			(size 0.3 1.125)
			(layers "F.Cu" "F.Mask" "F.Paste")
			(net 732 "/DC-DC Converters/QDCDC2_VCC")
			(pinfunction "VCC")
			(pintype "input")
		)
		(pad "26" smd rect
			(at 0.972 -3.138 180)
			(size 0.3 1.125)
			(layers "F.Cu" "F.Mask" "F.Paste")
			(net 954 "/DC-DC Converters/QDCDC2_GPIO")
			(pinfunction "GPIO")
			(pintype "input")
		)
		(pad "27" smd rect
			(at 0.325 -3.138 180)
			(size 0.3 1.125)
			(layers "F.Cu" "F.Mask" "F.Paste")
			(net 1 "GND")
			(pinfunction "GND")
			(pintype "passive")
		)
		(pad "28" smd rect
			(at -0.328 -3.138 180)
			(size 0.3 1.125)
			(layers "F.Cu" "F.Mask" "F.Paste")
			(net 702 "VDC")
			(pinfunction "VIN")
			(pintype "input")
		)
		(pad "29" smd rect
			(at -0.975 -3.138 180)
			(size 0.3 1.125)
			(layers "F.Cu" "F.Mask" "F.Paste")
			(net 702 "VDC")
			(pinfunction "VIN")
			(pintype "passive")
		)
		(pad "30" smd rect
			(at -1.625 -3.138 180)
			(size 0.3 1.125)
			(layers "F.Cu" "F.Mask" "F.Paste")
			(net 1 "GND")
			(pinfunction "SGND2")
			(pintype "power_out")
		)
		(pad "31" smd rect
			(at -2.275 -3.138 180)
			(size 0.3 1.125)
			(layers "F.Cu" "F.Mask" "F.Paste")
			(net 964 "/DC-DC Converters/FB7")
			(pinfunction "FB3")
			(pintype "input")
		)
		(pad "32" smd rect
			(at -2.926 -3.138 180)
			(size 0.3 1.125)
			(layers "F.Cu" "F.Mask" "F.Paste")
			(net 739 "/DC-DC Converters/5V_local")
			(pinfunction "VOUT3")
			(pintype "passive")
		)
		(pad "33" smd rect
			(at -0.863 -0.863 180)
			(size 1.725 1.725)
			(layers "F.Cu" "F.Mask" "F.Paste")
			(net 1 "GND")
			(pinfunction "GND")
			(pintype "passive")
			(solder_paste_margin -0.1)
		)
		(pad "33" smd rect
			(at -0.863 0.86 180)
			(size 1.725 1.725)
			(layers "F.Cu" "F.Mask" "F.Paste")
			(net 1 "GND")
			(pinfunction "GND")
			(pintype "passive")
			(solder_paste_margin -0.1)
		)
		(pad "33" smd rect
			(at 0.86 -0.863 180)
			(size 1.725 1.725)
			(layers "F.Cu" "F.Mask" "F.Paste")
			(net 1 "GND")
			(pinfunction "GND")
			(pintype "passive")
			(solder_paste_margin -0.1)
		)
		(pad "33" smd rect
			(at 0.86 0.86 180)
			(size 1.725 1.725)
			(layers "F.Cu" "F.Mask" "F.Paste")
			(net 1 "GND")
			(pinfunction "GND")
			(pintype "passive")
			(solder_paste_margin -0.1)
		)
	)
	(footprint "antmicro-footprints:C_0402_1005Metric"
		(layer "F.Cu")
		(at 221.5 146.7)
		(descr "Capacitor SMD 0402")
		(tags "capacitor SMD 0402")
		(property "Reference" "C257"
			(at 0.75 0.4 0)
			(layer "F.SilkS")
			(effects
				(font
					(size 0.7 0.7)
					(thickness 0.15)
				)
				(justify left bottom)
			)
		)
		(property "Value" "C_100n_0402"
			(at 0 1.169 0)
			(layer "F.Fab")
			(effects
				(font
					(size 0.7 0.7)
					(thickness 0.15)
				)
				(justify left bottom)
			)
		)
		(property "Description" "SMD Multilayer Ceramic Capacitor, 0.1 µF, 50 V, 0402 [1005 Metric], ± 10%, X5R, GRM Series"
			(at 0 0 0)
			(layer "F.Fab")
			(hide yes)
			(effects
				(font
					(size 1.27 1.27)
					(thickness 0.15)
				)
			)
		)
		(property "Author" "Antmicro"
			(at 0 0 0)
			(layer "F.Fab")
			(hide yes)
			(effects
				(font
					(size 1 1)
					(thickness 0.15)
				)
			)
		)
		(property "Dielectric" "X5R"
			(at 0 0 0)
			(layer "F.Fab")
			(hide yes)
			(effects
				(font
					(size 1 1)
					(thickness 0.15)
				)
			)
		)
		(property "License" "Apache-2.0"
			(at 0 0 0)
			(layer "F.Fab")
			(hide yes)
			(effects
				(font
					(size 1 1)
					(thickness 0.15)
				)
			)
		)
		(property "MPN" "GRM155R61H104KE14D"
			(at 0 0 0)
			(layer "F.Fab")
			(hide yes)
			(effects
				(font
					(size 1 1)
					(thickness 0.15)
				)
			)
		)
		(property "Manufacturer" "Murata"
			(at 0 0 0)
			(layer "F.Fab")
			(hide yes)
			(effects
				(font
					(size 1 1)
					(thickness 0.15)
				)
			)
		)
		(property "Val" "100n"
			(at 0 0 0)
			(layer "F.Fab")
			(hide yes)
			(effects
				(font
					(size 1 1)
					(thickness 0.15)
				)
			)
		)
		(property "Voltage" "50V"
			(at 0 0 0)
			(layer "F.Fab")
			(hide yes)
			(effects
				(font
					(size 1 1)
					(thickness 0.15)
				)
			)
		)
		(sheetname "HDMI + Ethernet")
		(sheetfile "hdmi-ethernet.kicad_sch")
		(attr smd)
		(fp_rect
			(start -0.925 -0.47)
			(end 0.925 0.47)
			(stroke
				(width 0.05)
				(type default)
			)
			(fill no)
			(layer "F.CrtYd")
		)
		(fp_line
			(start -0.494 -0.25)
			(end 0.504 -0.25)
			(stroke
				(width 0.15)
				(type solid)
			)
			(layer "F.Fab")
		)
		(fp_line
			(start -0.494 0.248)
			(end -0.494 -0.25)
			(stroke
				(width 0.15)
				(type solid)
			)
			(layer "F.Fab")
		)
		(fp_line
			(start 0.504 -0.25)
			(end 0.504 0.248)
			(stroke
				(width 0.15)
				(type solid)
			)
			(layer "F.Fab")
		)
		(fp_line
			(start 0.504 0.248)
			(end -0.494 0.248)
			(stroke
				(width 0.15)
				(type solid)
			)
			(layer "F.Fab")
		)
		(pad "1" smd roundrect
			(at -0.48 0)
			(size 0.59 0.64)
			(layers "F.Cu" "F.Mask" "F.Paste")
			(roundrect_rratio 0.25)
			(net 1 "GND")
			(pintype "passive")
		)
		(pad "2" smd roundrect
			(at 0.48 0)
			(size 0.59 0.64)
			(layers "F.Cu" "F.Mask" "F.Paste")
			(roundrect_rratio 0.25)
			(net 26 "+1V8")
			(pintype "passive")
		)
	)
	(footprint "antmicro-footprints:C_0402_1005Metric"
		(layer "F.Cu")
		(at 201.703752 100.9115)
		(descr "Capacitor SMD 0402")
		(tags "capacitor SMD 0402")
		(property "Reference" "C285"
			(at 4.296248 8.0885 0)
			(layer "F.SilkS")
			(effects
				(font
					(size 0.7 0.7)
					(thickness 0.15)
				)
				(justify left bottom)
			)
		)
		(property "Value" "C_10u_0402"
			(at 0 1.4 0)
			(layer "F.Fab")
			(effects
				(font
					(size 0.7 0.7)
					(thickness 0.15)
				)
				(justify left bottom)
			)
		)
		(property "Description" "SMD Multilayer Ceramic Capacitor, 10 µF, 6.3 V, 0402 [1005 Metric], ± 20%, X5R, CC Series"
			(at 0 0 0)
			(layer "F.Fab")
			(hide yes)
			(effects
				(font
					(size 1.27 1.27)
					(thickness 0.15)
				)
			)
		)
		(property "Author" "Antmicro"
			(at 0 0 0)
			(layer "F.Fab")
			(hide yes)
			(effects
				(font
					(size 1 1)
					(thickness 0.15)
				)
			)
		)
		(property "Dielectric" ""
			(at 0 0 0)
			(layer "F.Fab")
			(hide yes)
			(effects
				(font
					(size 1 1)
					(thickness 0.15)
				)
			)
		)
		(property "License" "Apache-2.0"
			(at 0 0 0)
			(layer "F.Fab")
			(hide yes)
			(effects
				(font
					(size 1 1)
					(thickness 0.15)
				)
			)
		)
		(property "MPN" "CC0402MRX5R5BB106"
			(at 0 0 0)
			(layer "F.Fab")
			(hide yes)
			(effects
				(font
					(size 1 1)
					(thickness 0.15)
				)
			)
		)
		(property "Manufacturer" "YAGEO"
			(at 0 0 0)
			(layer "F.Fab")
			(hide yes)
			(effects
				(font
					(size 1 1)
					(thickness 0.15)
				)
			)
		)
		(property "Val" "10u"
			(at 0 0 0)
			(layer "F.Fab")
			(hide yes)
			(effects
				(font
					(size 1 1)
					(thickness 0.15)
				)
			)
		)
		(property "Voltage" ""
			(at 0 0 0)
			(layer "F.Fab")
			(hide yes)
			(effects
				(font
					(size 1 1)
					(thickness 0.15)
				)
			)
		)
		(sheetname "HDMI + Ethernet")
		(sheetfile "hdmi-ethernet.kicad_sch")
		(attr smd)
		(fp_rect
			(start -0.925 -0.47)
			(end 0.925 0.47)
			(stroke
				(width 0.05)
				(type default)
			)
			(fill no)
			(layer "F.CrtYd")
		)
		(fp_line
			(start -0.494 -0.25)
			(end 0.504 -0.25)
			(stroke
				(width 0.15)
				(type solid)
			)
			(layer "F.Fab")
		)
		(fp_line
			(start -0.494 0.248)
			(end -0.494 -0.25)
			(stroke
				(width 0.15)
				(type solid)
			)
			(layer "F.Fab")
		)
		(fp_line
			(start 0.504 -0.25)
			(end 0.504 0.248)
			(stroke
				(width 0.15)
				(type solid)
			)
			(layer "F.Fab")
		)
		(fp_line
			(start 0.504 0.248)
			(end -0.494 0.248)
			(stroke
				(width 0.15)
				(type solid)
			)
			(layer "F.Fab")
		)
		(pad "1" smd roundrect
			(at -0.48 0)
			(size 0.59 0.64)
			(layers "F.Cu" "F.Mask" "F.Paste")
			(roundrect_rratio 0.25)
			(net 1 "GND")
			(pintype "passive")
		)
		(pad "2" smd roundrect
			(at 0.48 0)
			(size 0.59 0.64)
			(layers "F.Cu" "F.Mask" "F.Paste")
			(roundrect_rratio 0.25)
			(net 728 "/HDMI + Ethernet/GBE_AVDDL{slash}PLL")
			(pintype "passive")
		)
	)
)
